# T6G (Grand Teton) — schematic netlist excerpt (pin names and nets, part order shuffled) for the footprints in the layout excerpt that follows; sources: Cadence DE-HDL packaged netlist, KiCad conversion of 04192023_DAF0TMB3IC0_F0TG_MB_C_brd_V02_OCP.brd

R3340  Q_RES  33.2 1% CHIP  pkg 0402LF  page 151 : A = SMB_HOST_CLK_3V3AUX_SCL ; B = SMB_HOST_CLK_GEN2_3V3AUX_SCL
PC6014  Q_CAP  22UF 16V 20% X6S  pkg C0805  page 269 : A = SW_P12V_AUX_P1V8_AUX_FLT ; B = GND
R191  Q_RES  0 5% EMPTY  pkg 0402LF  page 55 : A = FM_CPU1_SLP_S5_N ; B = CPU1_SLP_S5_N

(kicad_pcb
	(version 20260206)
	(generator "pcbnew")
	(generator_version "10.0")
	(general
		(thickness 1.6)
		(legacy_teardrops no)
	)
	(paper "A4")
	(title_block
		(title "04192023_DAF0TMB3IC0_F0TG_MB_C_brd_V02_OCP.brd")
		(comment 1 "Grand Teton / footprints 1498-1500 of 8354")
	)
	(layers
		(0 "F.Cu" signal "TOP")
		(4 "In1.Cu" signal "GND")
		(6 "In2.Cu" signal "IN1")
		(8 "In3.Cu" signal "GND1")
		(10 "In4.Cu" signal "IN2")
		(12 "In5.Cu" signal "GND2")
		(14 "In6.Cu" signal "IN3")
		(16 "In7.Cu" signal "GND3")
		(18 "In8.Cu" signal "VCC")
		(20 "In9.Cu" signal "VCC1")
		(22 "In10.Cu" signal "GND4")
		(24 "In11.Cu" signal "IN4")
		(26 "In12.Cu" signal "GND5")
		(28 "In13.Cu" signal "IN5")
		(30 "In14.Cu" signal "GND6")
		(32 "In15.Cu" signal "IN6")
		(34 "In16.Cu" signal "GND7")
		(2 "B.Cu" signal "BOTTOM")
		(9 "F.Adhes" user "F.Adhesive")
		(11 "B.Adhes" user "B.Adhesive")
		(13 "F.Paste" user "Package Geometry/Pastemask Top")
		(15 "B.Paste" user "Package Geometry/Pastemask Bottom")
		(5 "F.SilkS" user "Ref Des/Silkscreen Top")
		(7 "B.SilkS" user "Ref Des/Silkscreen Bottom")
		(1 "F.Mask" user "Board Geometry/Soldermask Top")
		(3 "B.Mask" user "Board Geometry/Soldermask Bottom")
		(17 "Dwgs.User" user "User.Drawings")
		(19 "Cmts.User" user "User.Comments")
		(21 "Eco1.User" user "User.Eco1")
		(23 "Eco2.User" user "User.Eco2")
		(25 "Edge.Cuts" user "Board Geometry/Outline")
		(27 "Margin" user)
		(31 "F.CrtYd" user "Package Geometry/Place Bound Top")
		(29 "B.CrtYd" user "Package Geometry/Place Bound Bottom")
		(35 "F.Fab" user "Ref Des/Assembly Top")
		(33 "B.Fab" user "Ref Des/Assembly Bottom")
	)
	(footprint ""
		(layer "F.Cu")
		(at 12.319508 -128.593088 90)
		(property "Reference" "R3340"
			(at 0 0 90)
			(layer "F.SilkS")
			(hide yes)
			(effects
				(font
					(size 1.27 1.27)
				)
			)
		)
		(property "Value" ""
			(at 0 0 90)
			(layer "F.Fab")
			(effects
				(font
					(size 1.27 1.27)
				)
			)
		)
		(duplicate_pad_numbers_are_jumpers no)
		(fp_line
			(start 0.7874 -0.4064)
			(end 0.7874 0.4064)
			(stroke
				(width 0.1524)
				(type default)
			)
			(layer "F.SilkS")
		)
		(fp_line
			(start -0.7874 -0.4064)
			(end 0.7874 -0.4064)
			(stroke
				(width 0.1524)
				(type default)
			)
			(layer "F.SilkS")
		)
		(fp_line
			(start 0.7874 0.4064)
			(end -0.7874 0.4064)
			(stroke
				(width 0.1524)
				(type default)
			)
			(layer "F.SilkS")
		)
		(fp_line
			(start -0.7874 0.4064)
			(end -0.7874 -0.4064)
			(stroke
				(width 0.1524)
				(type default)
			)
			(layer "F.SilkS")
		)
		(fp_line
			(start -0.12065 -0.305054)
			(end -0.12065 -0.2794)
			(stroke
				(width 0.1)
				(type default)
			)
			(layer "F.Fab")
		)
		(fp_line
			(start -0.67945 -0.305054)
			(end -0.12065 -0.305054)
			(stroke
				(width 0.1)
				(type default)
			)
			(layer "F.Fab")
		)
		(fp_line
			(start 0.67945 -0.3048)
			(end 0.67945 0.3048)
			(stroke
				(width 0.1)
				(type default)
			)
			(layer "F.Fab")
		)
		(fp_line
			(start 0.12065 -0.3048)
			(end 0.67945 -0.3048)
			(stroke
				(width 0.1)
				(type default)
			)
			(layer "F.Fab")
		)
		(fp_line
			(start 0.12065 -0.2794)
			(end 0.12065 -0.3048)
			(stroke
				(width 0.1)
				(type default)
			)
			(layer "F.Fab")
		)
		(fp_line
			(start -0.12065 -0.2794)
			(end 0.12065 -0.2794)
			(stroke
				(width 0.1)
				(type default)
			)
			(layer "F.Fab")
		)
		(fp_line
			(start 0.120396 0.2794)
			(end -0.12065 0.2794)
			(stroke
				(width 0.1)
				(type default)
			)
			(layer "F.Fab")
		)
		(fp_line
			(start -0.12065 0.2794)
			(end -0.12065 0.3048)
			(stroke
				(width 0.1)
				(type default)
			)
			(layer "F.Fab")
		)
		(fp_line
			(start 0.67945 0.3048)
			(end 0.120396 0.3048)
			(stroke
				(width 0.1)
				(type default)
			)
			(layer "F.Fab")
		)
		(fp_line
			(start 0.120396 0.3048)
			(end 0.120396 0.2794)
			(stroke
				(width 0.1)
				(type default)
			)
			(layer "F.Fab")
		)
		(fp_line
			(start -0.12065 0.3048)
			(end -0.67945 0.3048)
			(stroke
				(width 0.1)
				(type default)
			)
			(layer "F.Fab")
		)
		(fp_line
			(start -0.67945 0.3048)
			(end -0.67945 -0.305054)
			(stroke
				(width 0.1)
				(type default)
			)
			(layer "F.Fab")
		)
		(pad "1" smd circle
			(at -0.40005 0 90)
			(size 0 0)
			(layers "F.Cu" "F.Mask" "F.Paste")
			(net "SMB_HOST_CLK_3V3AUX_SCL")
		)
		(pad "2" smd circle
			(at 0.40005 0 90)
			(size 0 0)
			(layers "F.Cu" "F.Mask" "F.Paste")
			(net "SMB_HOST_CLK_GEN2_3V3AUX_SCL")
		)
	)
	(footprint ""
		(layer "F.Cu")
		(at 139.890754 -79.273654 90)
		(property "Reference" "PC6014"
			(at 0 0 90)
			(layer "F.SilkS")
			(hide yes)
			(effects
				(font
					(size 1.27 1.27)
				)
			)
		)
		(property "Value" ""
			(at 0 0 90)
			(layer "F.Fab")
			(effects
				(font
					(size 1.27 1.27)
				)
			)
		)
		(duplicate_pad_numbers_are_jumpers no)
		(fp_line
			(start 1.524 -0.762)
			(end 1.524 0.762)
			(stroke
				(width 0.1524)
				(type default)
			)
			(layer "F.SilkS")
		)
		(fp_line
			(start -1.524 -0.762)
			(end 1.524 -0.762)
			(stroke
				(width 0.1524)
				(type default)
			)
			(layer "F.SilkS")
		)
		(fp_line
			(start 1.524 0.762)
			(end -1.524 0.762)
			(stroke
				(width 0.1524)
				(type default)
			)
			(layer "F.SilkS")
		)
		(fp_line
			(start -1.524 0.762)
			(end -1.524 -0.762)
			(stroke
				(width 0.1524)
				(type default)
			)
			(layer "F.SilkS")
		)
		(fp_line
			(start 1.1049 -0.724916)
			(end -1.1049 -0.724916)
			(stroke
				(width 0.1)
				(type default)
			)
			(layer "F.Fab")
		)
		(fp_line
			(start -1.1049 -0.724916)
			(end -1.1049 0.724916)
			(stroke
				(width 0.1)
				(type default)
			)
			(layer "F.Fab")
		)
		(fp_line
			(start 1.1049 0.724916)
			(end 1.1049 -0.724916)
			(stroke
				(width 0.1)
				(type default)
			)
			(layer "F.Fab")
		)
		(fp_line
			(start -1.1049 0.724916)
			(end 1.1049 0.724916)
			(stroke
				(width 0.1)
				(type default)
			)
			(layer "F.Fab")
		)
		(pad "1" smd rect
			(at -0.889 0 270)
			(size 1.016 1.27)
			(layers "F.Cu" "F.Mask" "F.Paste")
			(net "SW_P12V_AUX_P1V8_AUX_FLT")
		)
		(pad "2" smd rect
			(at 0.889 0 270)
			(size 1.016 1.27)
			(layers "F.Cu" "F.Mask" "F.Paste")
			(net "GND")
		)
	)
	(footprint ""
		(layer "F.Cu")
		(at 177.927 -129.377948 90)
		(property "Reference" "R191"
			(at 0 0 90)
			(layer "F.SilkS")
			(hide yes)
			(effects
				(font
					(size 1.27 1.27)
				)
			)
		)
		(property "Value" ""
			(at 0 0 90)
			(layer "F.Fab")
			(effects
				(font
					(size 1.27 1.27)
				)
			)
		)
		(duplicate_pad_numbers_are_jumpers no)
		(fp_line
			(start 0.7874 -0.4064)
			(end 0.7874 0.4064)
			(stroke
				(width 0.1524)
				(type default)
			)
			(layer "F.SilkS")
		)
		(fp_line
			(start -0.7874 -0.4064)
			(end 0.7874 -0.4064)
			(stroke
				(width 0.1524)
				(type default)
			)
			(layer "F.SilkS")
		)
		(fp_line
			(start 0.7874 0.4064)
			(end -0.7874 0.4064)
			(stroke
				(width 0.1524)
				(type default)
			)
			(layer "F.SilkS")
		)
		(fp_line
			(start -0.7874 0.4064)
			(end -0.7874 -0.4064)
			(stroke
				(width 0.1524)
				(type default)
			)
			(layer "F.SilkS")
		)
		(fp_line
			(start -0.12065 -0.305054)
			(end -0.12065 -0.2794)
			(stroke
				(width 0.1)
				(type default)
			)
			(layer "F.Fab")
		)
		(fp_line
			(start -0.67945 -0.305054)
			(end -0.12065 -0.305054)
			(stroke
				(width 0.1)
				(type default)
			)
			(layer "F.Fab")
		)
		(fp_line
			(start 0.67945 -0.3048)
			(end 0.67945 0.3048)
			(stroke
				(width 0.1)
				(type default)
			)
			(layer "F.Fab")
		)
		(fp_line
			(start 0.12065 -0.3048)
			(end 0.67945 -0.3048)
			(stroke
				(width 0.1)
				(type default)
			)
			(layer "F.Fab")
		)
		(fp_line
			(start 0.12065 -0.2794)
			(end 0.12065 -0.3048)
			(stroke
				(width 0.1)
				(type default)
			)
			(layer "F.Fab")
		)
		(fp_line
			(start -0.12065 -0.2794)
			(end 0.12065 -0.2794)
			(stroke
				(width 0.1)
				(type default)
			)
			(layer "F.Fab")
		)
		(fp_line
			(start 0.120396 0.2794)
			(end -0.12065 0.2794)
			(stroke
				(width 0.1)
				(type default)
			)
			(layer "F.Fab")
		)
		(fp_line
			(start -0.12065 0.2794)
			(end -0.12065 0.3048)
			(stroke
				(width 0.1)
				(type default)
			)
			(layer "F.Fab")
		)
		(fp_line
			(start 0.67945 0.3048)
			(end 0.120396 0.3048)
			(stroke
				(width 0.1)
				(type default)
			)
			(layer "F.Fab")
		)
		(fp_line
			(start 0.120396 0.3048)
			(end 0.120396 0.2794)
			(stroke
				(width 0.1)
				(type default)
			)
			(layer "F.Fab")
		)
		(fp_line
			(start -0.12065 0.3048)
			(end -0.67945 0.3048)
			(stroke
				(width 0.1)
				(type default)
			)
			(layer "F.Fab")
		)
		(fp_line
			(start -0.67945 0.3048)
			(end -0.67945 -0.305054)
			(stroke
				(width 0.1)
				(type default)
			)
			(layer "F.Fab")
		)
		(pad "1" smd circle
			(at -0.40005 0 90)
			(size 0 0)
			(layers "F.Cu" "F.Mask" "F.Paste")
			(net "FM_CPU1_SLP_S5_N")
		)
		(pad "2" smd circle
			(at 0.40005 0 90)
			(size 0 0)
			(layers "F.Cu" "F.Mask" "F.Paste")
			(net "CPU1_SLP_S5_N")
		)
	)
)
